FILE_TYPE = CONNECTIVITY;
{Allegro Design Entry HDL 17.2-2016 S081 (4005846) 1/11/2022}
"PAGE_NUMBER" = 21;
0"NC";
1"M_B_CPU0_SA_CA<6:0>";
2"M_B_CPU0_SA_CS_N<3:0>";
3"M_B_CPU0_SA_DQS_DN<9:0>";
4"M_B_CPU0_SA_DQS_DP<9:0>";
5"M_B_CPU0_SB_CA<6:0>";
6"M_B_CPU0_SB_CS_N<3:0>";
7"M_B_CPU0_SB_DQS_DN<9:0>";
8"M_B_CPU0_SB_DQS_DP<9:0>";
9"M_B_CPU0_SB_CB<7:0>";
10"M_B_CPU0_SB_DQ<31:0>";
11"M_B_CPU0_SA_CB<7:0>";
12"M_B_CPU0_SA_DQ<31:0>";
13"M_B_CPU0_CLK_DP<1:0>";
14"M_B_CPU0_CLK_DN<1:0>";
15"M_B_CPU0_CLK_DN<1>";
16"M_B_CPU0_CLK_DN<0>";
17"M_B_CPU0_CLK_DP<1>";
18"M_B_CPU0_CLK_DP<0>";
19"M_B_CPU0_SA_DQ<31>";
20"M_B_CPU0_SA_DQ<30>";
21"M_B_CPU0_SA_DQ<29>";
22"M_B_CPU0_SA_DQ<28>";
23"M_B_CPU0_SA_DQ<27>";
24"M_B_CPU0_SA_DQ<26>";
25"M_B_CPU0_SA_DQ<25>";
26"M_B_CPU0_SA_DQ<24>";
27"M_B_CPU0_SA_DQ<23>";
28"M_B_CPU0_SA_DQ<22>";
29"M_B_CPU0_SA_DQ<21>";
30"M_B_CPU0_SA_DQ<20>";
31"M_B_CPU0_SA_DQ<19>";
32"M_B_CPU0_SA_DQ<18>";
33"M_B_CPU0_SA_DQ<17>";
34"M_B_CPU0_SA_DQ<16>";
35"M_B_CPU0_SA_DQ<15>";
36"M_B_CPU0_SA_DQ<14>";
37"M_B_CPU0_SA_DQ<13>";
38"M_B_CPU0_SA_DQ<12>";
39"M_B_CPU0_SA_DQ<11>";
40"M_B_CPU0_SA_DQ<10>";
41"M_B_CPU0_SA_DQ<9>";
42"M_B_CPU0_SA_DQ<8>";
43"M_B_CPU0_SA_DQ<7>";
44"M_B_CPU0_SA_DQ<6>";
45"M_B_CPU0_SA_DQ<5>";
46"M_B_CPU0_SA_DQ<4>";
47"M_B_CPU0_SA_DQ<3>";
48"M_B_CPU0_SA_DQ<2>";
49"M_B_CPU0_SA_DQ<1>";
50"M_B_CPU0_SA_DQ<0>";
51"M_B_CPU0_SA_CB<7>";
52"M_B_CPU0_SA_CB<6>";
53"M_B_CPU0_SA_CB<5>";
54"M_B_CPU0_SA_CB<4>";
55"M_B_CPU0_SA_CB<3>";
56"M_B_CPU0_SA_CB<2>";
57"M_B_CPU0_SA_CB<1>";
58"M_B_CPU0_SA_CB<0>";
59"M_B_CPU0_SB_DQ<31>";
60"M_B_CPU0_SB_DQ<30>";
61"M_B_CPU0_SB_DQ<29>";
62"M_B_CPU0_SB_DQ<28>";
63"M_B_CPU0_SB_DQ<27>";
64"M_B_CPU0_SB_DQ<26>";
65"M_B_CPU0_SB_DQ<25>";
66"M_B_CPU0_SB_DQ<24>";
67"M_B_CPU0_SB_DQ<23>";
68"M_B_CPU0_SB_DQ<22>";
69"M_B_CPU0_SB_DQ<21>";
70"M_B_CPU0_SB_DQ<20>";
71"M_B_CPU0_SB_DQ<19>";
72"M_B_CPU0_SB_DQ<18>";
73"M_B_CPU0_SB_DQ<17>";
74"M_B_CPU0_SB_DQ<16>";
75"M_B_CPU0_SB_DQ<15>";
76"M_B_CPU0_SB_DQ<14>";
77"M_B_CPU0_SB_DQ<13>";
78"M_B_CPU0_SB_DQ<12>";
79"M_B_CPU0_SB_DQ<11>";
80"M_B_CPU0_SB_DQ<10>";
81"M_B_CPU0_SB_DQ<9>";
82"M_B_CPU0_SB_DQ<8>";
83"M_B_CPU0_SB_DQ<7>";
84"M_B_CPU0_SB_DQ<6>";
85"M_B_CPU0_SB_DQ<5>";
86"M_B_CPU0_SB_DQ<4>";
87"M_B_CPU0_SB_DQ<3>";
88"M_B_CPU0_SB_DQ<2>";
89"M_B_CPU0_SB_DQ<1>";
90"M_B_CPU0_SB_DQ<0>";
91"M_B_CPU0_SB_CB<7>";
92"M_B_CPU0_SB_CB<6>";
93"M_B_CPU0_SB_CB<5>";
94"M_B_CPU0_SB_CB<4>";
95"M_B_CPU0_SB_CB<3>";
96"M_B_CPU0_SB_CB<2>";
97"M_B_CPU0_SB_CB<1>";
98"M_B_CPU0_SB_CB<0>";
99"M_B_CPU0_SB_PAR";
100"M_B_CPU0_SB_DQS_DP<0>";
101"M_B_CPU0_SB_DQS_DP<1>";
102"M_B_CPU0_SB_DQS_DP<2>";
103"M_B_CPU0_SB_DQS_DP<3>";
104"M_B_CPU0_SB_DQS_DP<4>";
105"M_B_CPU0_SB_DQS_DP<5>";
106"M_B_CPU0_SB_DQS_DP<6>";
107"M_B_CPU0_SB_DQS_DP<7>";
108"M_B_CPU0_SB_DQS_DP<8>";
109"M_B_CPU0_SB_DQS_DP<9>";
110"M_B_CPU0_SB_DQS_DN<0>";
111"M_B_CPU0_SB_DQS_DN<1>";
112"M_B_CPU0_SB_DQS_DN<2>";
113"M_B_CPU0_SB_DQS_DN<3>";
114"M_B_CPU0_SB_DQS_DN<4>";
115"M_B_CPU0_SB_DQS_DN<5>";
116"M_B_CPU0_SB_DQS_DN<6>";
117"M_B_CPU0_SB_DQS_DN<7>";
118"M_B_CPU0_SB_DQS_DN<8>";
119"M_B_CPU0_SB_DQS_DN<9>";
120"M_B_CPU0_SB_CS_N<0>";
121"M_B_CPU0_SB_CS_N<1>";
122"M_B_CPU0_SB_CS_N<2>";
123"M_B_CPU0_SB_CS_N<3>";
124"M_B_CPU0_SB_CA<0>";
125"M_B_CPU0_SB_CA<1>";
126"M_B_CPU0_SB_CA<2>";
127"M_B_CPU0_SB_CA<3>";
128"M_B_CPU0_SB_CA<4>";
129"M_B_CPU0_SB_CA<5>";
130"M_B_CPU0_SB_CA<6>";
131"M_B_CPU0_SA_PAR";
132"M_B_CPU0_SA_DQS_DP<0>";
133"M_B_CPU0_SA_DQS_DP<1>";
134"M_B_CPU0_SA_DQS_DP<2>";
135"M_B_CPU0_SA_DQS_DP<3>";
136"M_B_CPU0_SA_DQS_DP<4>";
137"M_B_CPU0_SA_DQS_DP<5>";
138"M_B_CPU0_SA_DQS_DP<6>";
139"M_B_CPU0_SA_DQS_DP<7>";
140"M_B_CPU0_SA_DQS_DP<8>";
141"M_B_CPU0_SA_DQS_DP<9>";
142"M_B_CPU0_SA_DQS_DN<0>";
143"M_B_CPU0_SA_DQS_DN<1>";
144"M_B_CPU0_SA_DQS_DN<2>";
145"M_B_CPU0_SA_DQS_DN<3>";
146"M_B_CPU0_SA_DQS_DN<4>";
147"M_B_CPU0_SA_DQS_DN<5>";
148"M_B_CPU0_SA_DQS_DN<6>";
149"M_B_CPU0_SA_DQS_DN<7>";
150"M_B_CPU0_SA_DQS_DN<8>";
151"M_B_CPU0_SA_DQS_DN<9>";
152"M_B_CPU0_SA_CS_N<0>";
153"M_B_CPU0_SA_CS_N<1>";
154"M_B_CPU0_SA_CS_N<2>";
155"M_B_CPU0_SA_CS_N<3>";
156"M_B_CPU0_SA_CA<0>";
157"M_B_CPU0_SA_CA<1>";
158"M_B_CPU0_SA_CA<2>";
159"M_B_CPU0_SA_CA<3>";
160"M_B_CPU0_SA_CA<4>";
161"M_B_CPU0_SA_CA<5>";
162"M_B_CPU0_SA_CA<6>";
163"M_B_CPU0_SB_RSP<0>";
164"M_B_CPU0_SB_RSP<1>";
165"M_B_CPU0_SA_RSP<0>";
166"M_B_CPU0_SA_RSP<1>";
167"M_B_CPU0_ALERT_N";
%"TAP"
"1","(-175,75)","2","standard","I10";
;
CDS_LIB"standard"
BODY_TYPE"PLUMBING"
HDL_TAP"TRUE";
"B \NAC \NWC"9;
"S \NAC"
BN"1"97;
%"TAP"
"1","(3250,675)","0","standard","I100";
;
CDS_LIB"standard"
BODY_TYPE"PLUMBING"
HDL_TAP"TRUE";
"B \NAC \NWC"2;
"S \NAC"
BN"3"155;
%"TAP"
"1","(3250,925)","0","standard","I101";
;
CDS_LIB"standard"
BODY_TYPE"PLUMBING"
HDL_TAP"TRUE";
"B \NAC \NWC"5;
"S \NAC"
BN"1"125;
%"TAP"
"1","(3250,875)","0","standard","I102";
;
CDS_LIB"standard"
BODY_TYPE"PLUMBING"
HDL_TAP"TRUE";
"B \NAC \NWC"5;
"S \NAC"
BN"0"124;
%"TAP"
"1","(3250,975)","0","standard","I103";
;
CDS_LIB"standard"
BODY_TYPE"PLUMBING"
HDL_TAP"TRUE";
"B \NAC \NWC"5;
"S \NAC"
BN"2"126;
%"TAP"
"1","(3250,1025)","0","standard","I104";
;
CDS_LIB"standard"
BODY_TYPE"PLUMBING"
HDL_TAP"TRUE";
"B \NAC \NWC"5;
"S \NAC"
BN"3"127;
%"TAP"
"1","(3250,1175)","0","standard","I105";
;
CDS_LIB"standard"
BODY_TYPE"PLUMBING"
HDL_TAP"TRUE";
"B \NAC \NWC"5;
"S \NAC"
BN"6"130;
%"TAP"
"1","(3250,1125)","0","standard","I106";
;
CDS_LIB"standard"
BODY_TYPE"PLUMBING"
HDL_TAP"TRUE";
"B \NAC \NWC"5;
"S \NAC"
BN"5"129;
%"TAP"
"1","(3250,1075)","0","standard","I107";
;
CDS_LIB"standard"
BODY_TYPE"PLUMBING"
HDL_TAP"TRUE";
"B \NAC \NWC"5;
"S \NAC"
BN"4"128;
%"TAP"
"1","(3250,1375)","0","standard","I108";
;
CDS_LIB"standard"
BODY_TYPE"PLUMBING"
HDL_TAP"TRUE";
"B \NAC \NWC"1;
"S \NAC"
BN"0"156;
%"TAP"
"1","(3250,1425)","0","standard","I109";
;
CDS_LIB"standard"
BODY_TYPE"PLUMBING"
HDL_TAP"TRUE";
"B \NAC \NWC"1;
"S \NAC"
BN"1"157;
%"TAP"
"1","(-175,125)","2","standard","I11";
;
CDS_LIB"standard"
BODY_TYPE"PLUMBING"
HDL_TAP"TRUE";
"B \NAC \NWC"9;
"S \NAC"
BN"2"96;
%"TAP"
"1","(3250,1475)","0","standard","I110";
;
CDS_LIB"standard"
BODY_TYPE"PLUMBING"
HDL_TAP"TRUE";
"B \NAC \NWC"1;
"S \NAC"
BN"2"158;
%"TAP"
"1","(3250,1525)","0","standard","I111";
;
CDS_LIB"standard"
BODY_TYPE"PLUMBING"
HDL_TAP"TRUE";
"B \NAC \NWC"1;
"S \NAC"
BN"3"159;
%"TAP"
"1","(3250,1575)","0","standard","I112";
;
CDS_LIB"standard"
BODY_TYPE"PLUMBING"
HDL_TAP"TRUE";
"B \NAC \NWC"1;
"S \NAC"
BN"4"160;
%"TAP"
"1","(3250,1675)","0","standard","I113";
;
CDS_LIB"standard"
BODY_TYPE"PLUMBING"
HDL_TAP"TRUE";
"B \NAC \NWC"1;
"S \NAC"
BN"6"162;
%"TAP"
"1","(3250,1625)","0","standard","I114";
;
CDS_LIB"standard"
BODY_TYPE"PLUMBING"
HDL_TAP"TRUE";
"B \NAC \NWC"1;
"S \NAC"
BN"5"161;
%"TAP"
"1","(-175,225)","2","standard","I12";
;
CDS_LIB"standard"
BODY_TYPE"PLUMBING"
HDL_TAP"TRUE";
"B \NAC \NWC"9;
"S \NAC"
BN"4"94;
%"TAP"
"1","(3250,1825)","0","standard","I125";
;
CDS_LIB"standard"
BODY_TYPE"PLUMBING"
HDL_TAP"TRUE";
"B \NAC \NWC"7;
"S \NAC"
BN"0"110;
%"TAP"
"1","(3250,1925)","0","standard","I126";
;
CDS_LIB"standard"
BODY_TYPE"PLUMBING"
HDL_TAP"TRUE";
"B \NAC \NWC"7;
"S \NAC"
BN"2"112;
%"TAP"
"1","(3250,1875)","0","standard","I127";
;
CDS_LIB"standard"
BODY_TYPE"PLUMBING"
HDL_TAP"TRUE";
"B \NAC \NWC"7;
"S \NAC"
BN"1"111;
%"TAP"
"1","(3250,2025)","0","standard","I128";
;
CDS_LIB"standard"
BODY_TYPE"PLUMBING"
HDL_TAP"TRUE";
"B \NAC \NWC"7;
"S \NAC"
BN"4"114;
%"TAP"
"1","(3250,2075)","0","standard","I129";
;
CDS_LIB"standard"
BODY_TYPE"PLUMBING"
HDL_TAP"TRUE";
"B \NAC \NWC"7;
"S \NAC"
BN"5"115;
%"TAP"
"1","(-175,175)","2","standard","I13";
;
CDS_LIB"standard"
BODY_TYPE"PLUMBING"
HDL_TAP"TRUE";
"B \NAC \NWC"9;
"S \NAC"
BN"3"95;
%"TAP"
"1","(3250,1975)","0","standard","I130";
;
CDS_LIB"standard"
BODY_TYPE"PLUMBING"
HDL_TAP"TRUE";
"B \NAC \NWC"7;
"S \NAC"
BN"3"113;
%"TAP"
"1","(3250,2125)","0","standard","I131";
;
CDS_LIB"standard"
BODY_TYPE"PLUMBING"
HDL_TAP"TRUE";
"B \NAC \NWC"7;
"S \NAC"
BN"6"116;
%"TAP"
"1","(3250,2175)","0","standard","I132";
;
CDS_LIB"standard"
BODY_TYPE"PLUMBING"
HDL_TAP"TRUE";
"B \NAC \NWC"7;
"S \NAC"
BN"7"117;
%"TAP"
"1","(3250,2275)","0","standard","I133";
;
CDS_LIB"standard"
BODY_TYPE"PLUMBING"
HDL_TAP"TRUE";
"B \NAC \NWC"7;
"S \NAC"
BN"9"119;
%"TAP"
"1","(3250,2225)","0","standard","I134";
;
CDS_LIB"standard"
BODY_TYPE"PLUMBING"
HDL_TAP"TRUE";
"B \NAC \NWC"7;
"S \NAC"
BN"8"118;
%"TAP"
"1","(3250,2375)","0","standard","I135";
;
CDS_LIB"standard"
BODY_TYPE"PLUMBING"
HDL_TAP"TRUE";
"B \NAC \NWC"8;
"S \NAC"
BN"0"100;
%"TAP"
"1","(3250,2425)","0","standard","I136";
;
CDS_LIB"standard"
BODY_TYPE"PLUMBING"
HDL_TAP"TRUE";
"B \NAC \NWC"8;
"S \NAC"
BN"1"101;
%"TAP"
"1","(3250,2575)","0","standard","I137";
;
CDS_LIB"standard"
BODY_TYPE"PLUMBING"
HDL_TAP"TRUE";
"B \NAC \NWC"8;
"S \NAC"
BN"4"104;
%"TAP"
"1","(3250,2475)","0","standard","I138";
;
CDS_LIB"standard"
BODY_TYPE"PLUMBING"
HDL_TAP"TRUE";
"B \NAC \NWC"8;
"S \NAC"
BN"2"102;
%"TAP"
"1","(3250,2525)","0","standard","I139";
;
CDS_LIB"standard"
BODY_TYPE"PLUMBING"
HDL_TAP"TRUE";
"B \NAC \NWC"8;
"S \NAC"
BN"3"103;
%"TAP"
"1","(-175,275)","2","standard","I14";
;
CDS_LIB"standard"
BODY_TYPE"PLUMBING"
HDL_TAP"TRUE";
"B \NAC \NWC"9;
"S \NAC"
BN"5"93;
%"TAP"
"1","(3250,2675)","0","standard","I140";
;
CDS_LIB"standard"
BODY_TYPE"PLUMBING"
HDL_TAP"TRUE";
"B \NAC \NWC"8;
"S \NAC"
BN"6"106;
%"TAP"
"1","(3250,2625)","0","standard","I141";
;
CDS_LIB"standard"
BODY_TYPE"PLUMBING"
HDL_TAP"TRUE";
"B \NAC \NWC"8;
"S \NAC"
BN"5"105;
%"TAP"
"1","(3250,2775)","0","standard","I142";
;
CDS_LIB"standard"
BODY_TYPE"PLUMBING"
HDL_TAP"TRUE";
"B \NAC \NWC"8;
"S \NAC"
BN"8"108;
%"TAP"
"1","(3250,2825)","0","standard","I143";
;
CDS_LIB"standard"
BODY_TYPE"PLUMBING"
HDL_TAP"TRUE";
"B \NAC \NWC"8;
"S \NAC"
BN"9"109;
%"TAP"
"1","(3250,2725)","0","standard","I144";
;
CDS_LIB"standard"
BODY_TYPE"PLUMBING"
HDL_TAP"TRUE";
"B \NAC \NWC"8;
"S \NAC"
BN"7"107;
%"TAP"
"1","(3250,2975)","0","standard","I145";
;
CDS_LIB"standard"
BODY_TYPE"PLUMBING"
HDL_TAP"TRUE";
"B \NAC \NWC"3;
"S \NAC"
BN"0"142;
%"TAP"
"1","(3250,3075)","0","standard","I146";
;
CDS_LIB"standard"
BODY_TYPE"PLUMBING"
HDL_TAP"TRUE";
"B \NAC \NWC"3;
"S \NAC"
BN"2"144;
%"TAP"
"1","(3250,3025)","0","standard","I147";
;
CDS_LIB"standard"
BODY_TYPE"PLUMBING"
HDL_TAP"TRUE";
"B \NAC \NWC"3;
"S \NAC"
BN"1"143;
%"TAP"
"1","(3250,3175)","0","standard","I148";
;
CDS_LIB"standard"
BODY_TYPE"PLUMBING"
HDL_TAP"TRUE";
"B \NAC \NWC"3;
"S \NAC"
BN"4"146;
%"TAP"
"1","(3250,3225)","0","standard","I149";
;
CDS_LIB"standard"
BODY_TYPE"PLUMBING"
HDL_TAP"TRUE";
"B \NAC \NWC"3;
"S \NAC"
BN"5"147;
%"TAP"
"1","(-175,475)","2","standard","I15";
;
CDS_LIB"standard"
BODY_TYPE"PLUMBING"
HDL_TAP"TRUE";
"B \NAC \NWC"10;
"S \NAC"
BN"1"89;
%"TAP"
"1","(3250,3125)","0","standard","I150";
;
CDS_LIB"standard"
BODY_TYPE"PLUMBING"
HDL_TAP"TRUE";
"B \NAC \NWC"3;
"S \NAC"
BN"3"145;
%"TAP"
"1","(3250,3275)","0","standard","I151";
;
CDS_LIB"standard"
BODY_TYPE"PLUMBING"
HDL_TAP"TRUE";
"B \NAC \NWC"3;
"S \NAC"
BN"6"148;
%"TAP"
"1","(3250,3325)","0","standard","I152";
;
CDS_LIB"standard"
BODY_TYPE"PLUMBING"
HDL_TAP"TRUE";
"B \NAC \NWC"3;
"S \NAC"
BN"7"149;
%"TAP"
"1","(3250,3425)","0","standard","I153";
;
CDS_LIB"standard"
BODY_TYPE"PLUMBING"
HDL_TAP"TRUE";
"B \NAC \NWC"3;
"S \NAC"
BN"9"151;
%"TAP"
"1","(3250,3375)","0","standard","I154";
;
CDS_LIB"standard"
BODY_TYPE"PLUMBING"
HDL_TAP"TRUE";
"B \NAC \NWC"3;
"S \NAC"
BN"8"150;
%"TAP"
"1","(3250,3575)","0","standard","I155";
;
CDS_LIB"standard"
BODY_TYPE"PLUMBING"
HDL_TAP"TRUE";
"B \NAC \NWC"4;
"S \NAC"
BN"1"133;
%"TAP"
"1","(3250,3525)","0","standard","I156";
;
CDS_LIB"standard"
BODY_TYPE"PLUMBING"
HDL_TAP"TRUE";
"B \NAC \NWC"4;
"S \NAC"
BN"0"132;
%"TAP"
"1","(3250,3725)","0","standard","I157";
;
CDS_LIB"standard"
BODY_TYPE"PLUMBING"
HDL_TAP"TRUE";
"B \NAC \NWC"4;
"S \NAC"
BN"4"136;
%"TAP"
"1","(3250,3625)","0","standard","I158";
;
CDS_LIB"standard"
BODY_TYPE"PLUMBING"
HDL_TAP"TRUE";
"B \NAC \NWC"4;
"S \NAC"
BN"2"134;
%"TAP"
"1","(3250,3675)","0","standard","I159";
;
CDS_LIB"standard"
BODY_TYPE"PLUMBING"
HDL_TAP"TRUE";
"B \NAC \NWC"4;
"S \NAC"
BN"3"135;
%"TAP"
"1","(-175,425)","2","standard","I16";
;
CDS_LIB"standard"
BODY_TYPE"PLUMBING"
HDL_TAP"TRUE";
"B \NAC \NWC"10;
"S \NAC"
BN"0"90;
%"TAP"
"1","(3250,3825)","0","standard","I160";
;
CDS_LIB"standard"
BODY_TYPE"PLUMBING"
HDL_TAP"TRUE";
"B \NAC \NWC"4;
"S \NAC"
BN"6"138;
%"TAP"
"1","(3250,3775)","0","standard","I161";
;
CDS_LIB"standard"
BODY_TYPE"PLUMBING"
HDL_TAP"TRUE";
"B \NAC \NWC"4;
"S \NAC"
BN"5"137;
%"TAP"
"1","(3250,3875)","0","standard","I165";
;
CDS_LIB"standard"
BODY_TYPE"PLUMBING"
HDL_TAP"TRUE";
"B \NAC \NWC"4;
"S \NAC"
BN"7"139;
%"TAP"
"1","(3250,3925)","0","standard","I166";
;
CDS_LIB"standard"
BODY_TYPE"PLUMBING"
HDL_TAP"TRUE";
"B \NAC \NWC"4;
"S \NAC"
BN"8"140;
%"TAP"
"1","(3250,3975)","0","standard","I167";
;
CDS_LIB"standard"
BODY_TYPE"PLUMBING"
HDL_TAP"TRUE";
"B \NAC \NWC"4;
"S \NAC"
BN"9"141;
%"SOCKET4677_AZIF0045P001C01CS"
"9","(1550,1875)","0","pure_quanta","I169";
;
PART_NUMBER"DGA^7000023"
PART_TYPE"SMLF"
VALUE"SOCKET4677_AZIF0045-P001C01CS"
MATERIAL"IO"
$LOCATION"U2"
CDS_LIB"pure_quanta"
NEEDS_NO_SIZE"TRUE"
CDS_LMAN_SYM_OUTLINE"-1100,2250,1050,-2250"
CDS_LOCATION"U2"
$SEC"9"
CDS_SEC"9";
"DDR1_SB_PAR"
$PN"P42"99;
"DDR1_SB_ECC0"
$PN"J35"98;
"DDR1_SB_ECC1"
$PN"K34"97;
"DDR1_SB_ECC2"
$PN"N35"96;
"DDR1_SB_ECC3"
$PN"M34"95;
"DDR1_SB_ECC4"
$PN"K38"94;
"DDR1_SB_ECC5"
$PN"J37"93;
"DDR1_SB_ECC6"
$PN"M38"92;
"DDR1_SB_ECC7"
$PN"N37"91;
"DDR1_SB_DQS_DP0"
$PN"U27"100;
"DDR1_SB_DQS_DP1"
$PN"K24"101;
"DDR1_SB_DQS_DP2"
$PN"K18"102;
"DDR1_SB_DQS_DP3"
$PN"C15"103;
"DDR1_SB_DQS_DP4"
$PN"M36"104;
"DDR1_SB_DQS_DP5"
$PN"AA27"105;
"DDR1_SB_DQS_DP6"
$PN"P24"106;
"DDR1_SB_DQS_DP7"
$PN"P18"107;
"DDR1_SB_DQS_DP8"
$PN"G15"108;
"DDR1_SB_DQS_DP9"
$PN"H36"109;
"DDR1_SB_DQS_DN0 \B"
$PN"R27"110;
"DDR1_SB_DQS_DN1 \B"
$PN"H24"111;
"DDR1_SB_DQS_DN2 \B"
$PN"H18"112;
"DDR1_SB_DQS_DN3 \B"
$PN"A15"113;
"DDR1_SB_DQS_DN4 \B"
$PN"P36"114;
"DDR1_SB_DQS_DN5 \B"
$PN"W27"115;
"DDR1_SB_DQS_DN6 \B"
$PN"M24"116;
"DDR1_SB_DQS_DN7 \B"
$PN"M18"117;
"DDR1_SB_DQS_DN8 \B"
$PN"E15"118;
"DDR1_SB_DQS_DN9 \B"
$PN"K36"119;
"DDR1_SB_DQ0"
$PN"U29"90;
"DDR1_SB_DQ1"
$PN"T28"89;
"DDR1_SB_DQ2"
$PN"W29"88;
"DDR1_SB_DQ3"
$PN"Y28"87;
"DDR1_SB_DQ4"
$PN"T26"86;
"DDR1_SB_DQ5"
$PN"U25"85;
"DDR1_SB_DQ6"
$PN"Y26"84;
"DDR1_SB_DQ7"
$PN"W25"83;
"DDR1_SB_DQ8"
$PN"K26"82;
"DDR1_SB_DQ9"
$PN"J25"81;
"DDR1_SB_DQ10"
$PN"M26"80;
"DDR1_SB_DQ11"
$PN"N25"79;
"DDR1_SB_DQ12"
$PN"J23"78;
"DDR1_SB_DQ13"
$PN"K22"77;
"DDR1_SB_DQ14"
$PN"N23"76;
"DDR1_SB_DQ15"
$PN"M22"75;
"DDR1_SB_DQ16"
$PN"K20"74;
"DDR1_SB_DQ17"
$PN"J19"73;
"DDR1_SB_DQ18"
$PN"M20"72;
"DDR1_SB_DQ19"
$PN"N19"71;
"DDR1_SB_DQ20"
$PN"J17"70;
"DDR1_SB_DQ21"
$PN"K16"69;
"DDR1_SB_DQ22"
$PN"N17"68;
"DDR1_SB_DQ23"
$PN"M16"67;
"DDR1_SB_DQ24"
$PN"C17"66;
"DDR1_SB_DQ25"
$PN"B16"65;
"DDR1_SB_DQ26"
$PN"E17"64;
"DDR1_SB_DQ27"
$PN"F16"63;
"DDR1_SB_DQ28"
$PN"C13"62;
"DDR1_SB_DQ29"
$PN"E13"61;
"DDR1_SB_DQ30"
$PN"B14"60;
"DDR1_SB_DQ31"
$PN"F14"59;
"DDR1_SB_CS_N0 \B"
$PN"J41"120;
"DDR1_SB_CS_N1 \B"
$PN"K40"121;
"DDR1_SB_CS_N2 \B"
$PN"N41"122;
"DDR1_SB_CS_N3 \B"
$PN"M40"123;
"DDR1_SB_CA0"
$PN"T44"124;
"DDR1_SB_CA1"
$PN"U43"125;
"DDR1_SB_CA2"
$PN"K44"126;
"DDR1_SB_CA3"
$PN"M44"127;
"DDR1_SB_CA4"
$PN"J43"128;
"DDR1_SB_CA5"
$PN"N43"129;
"DDR1_SB_CA6"
$PN"H42"130;
"DDR1_SA_PAR"
$PN"W43"131;
"DDR1_SA_ECC0"
$PN"K57"58;
"DDR1_SA_ECC1"
$PN"J56"57;
"DDR1_SA_ECC2"
$PN"M57"56;
"DDR1_SA_ECC3"
$PN"N56"55;
"DDR1_SA_ECC4"
$PN"J54"54;
"DDR1_SA_ECC5"
$PN"K53"53;
"DDR1_SA_ECC6"
$PN"N54"52;
"DDR1_SA_ECC7"
$PN"M53"51;
"DDR1_SA_DQS_DP0"
$PN"K73"132;
"DDR1_SA_DQS_DP1"
$PN"U70"133;
"DDR1_SA_DQS_DP2"
$PN"K61"134;
"DDR1_SA_DQS_DP3"
$PN"U58"135;
"DDR1_SA_DQS_DP4"
$PN"K55"136;
"DDR1_SA_DQS_DP5"
$PN"P73"137;
"DDR1_SA_DQS_DP6"
$PN"W70"138;
"DDR1_SA_DQS_DP7"
$PN"P61"139;
"DDR1_SA_DQS_DP8"
$PN"W58"140;
"DDR1_SA_DQS_DP9"
$PN"P55"141;
"DDR1_SA_DQS_DN0 \B"
$PN"H73"142;
"DDR1_SA_DQS_DN1 \B"
$PN"R70"143;
"DDR1_SA_DQS_DN2 \B"
$PN"H61"144;
"DDR1_SA_DQS_DN3 \B"
$PN"R58"145;
"DDR1_SA_DQS_DN4 \B"
$PN"H55"146;
"DDR1_SA_DQS_DN5 \B"
$PN"M73"147;
"DDR1_SA_DQS_DN6 \B"
$PN"AA70"148;
"DDR1_SA_DQS_DN7 \B"
$PN"M61"149;
"DDR1_SA_DQS_DN8 \B"
$PN"AA58"150;
"DDR1_SA_DQS_DN9 \B"
$PN"M55"151;
"DDR1_SA_DQ0"
$PN"K75"50;
"DDR1_SA_DQ1"
$PN"J74"49;
"DDR1_SA_DQ2"
$PN"M75"48;
"DDR1_SA_DQ3"
$PN"N74"47;
"DDR1_SA_DQ4"
$PN"J72"46;
"DDR1_SA_DQ5"
$PN"K71"45;
"DDR1_SA_DQ6"
$PN"N72"44;
"DDR1_SA_DQ7"
$PN"M71"43;
"DDR1_SA_DQ8"
$PN"U72"42;
"DDR1_SA_DQ9"
$PN"T71"41;
"DDR1_SA_DQ10"
$PN"W72"40;
"DDR1_SA_DQ11"
$PN"Y71"39;
"DDR1_SA_DQ12"
$PN"T69"38;
"DDR1_SA_DQ13"
$PN"U68"37;
"DDR1_SA_DQ14"
$PN"Y69"36;
"DDR1_SA_DQ15"
$PN"W68"35;
"DDR1_SA_DQ16"
$PN"K63"34;
"DDR1_SA_DQ17"
$PN"J62"33;
"DDR1_SA_DQ18"
$PN"M63"32;
"DDR1_SA_DQ19"
$PN"N62"31;
"DDR1_SA_DQ20"
$PN"J60"30;
"DDR1_SA_DQ21"
$PN"K59"29;
"DDR1_SA_DQ22"
$PN"N60"28;
"DDR1_SA_DQ23"
$PN"M59"27;
"DDR1_SA_DQ24"
$PN"U60"26;
"DDR1_SA_DQ25"
$PN"T59"25;
"DDR1_SA_DQ26"
$PN"W60"24;
"DDR1_SA_DQ27"
$PN"Y59"23;
"DDR1_SA_DQ28"
$PN"T57"22;
"DDR1_SA_DQ29"
$PN"U56"21;
"DDR1_SA_DQ30"
$PN"Y57"20;
"DDR1_SA_DQ31"
$PN"W56"19;
"DDR1_SA_CS_N0 \B"
$PN"K51"152;
"DDR1_SA_CS_N1 \B"
$PN"J50"153;
"DDR1_SA_CS_N2 \B"
$PN"M51"154;
"DDR1_SA_CS_N3 \B"
$PN"N50"155;
"DDR1_SA_CA0"
$PN"H49"156;
"DDR1_SA_CA1"
$PN"P49"157;
"DDR1_SA_CA2"
$PN"J48"158;
"DDR1_SA_CA3"
$PN"N48"159;
"DDR1_SA_CA4"
$PN"K47"160;
"DDR1_SA_CA5"
$PN"M47"161;
"DDR1_SA_CA6"
$PN"Y44"162;
"DDR1_CLK_DP0"
$PN"U45"18;
"DDR1_CLK_DP1"
$PN"AA45"17;
"DDR1_CLK_DN0 \B"
$PN"R45"16;
"DDR1_CLK_DN1 \B"
$PN"W45"15;
"DDR1_B_RSP0"
$PN"AN48"163;
"DDR1_B_RSP1"
$PN"AP47"164;
"DDR1_A_RSP0"
$PN"AL48"165;
"DDR1_A_RSP1"
$PN"AK47"166;
"DDR1_ALERT_N \B"
$PN"AV49"167;
%"TAP"
"1","(-175,325)","2","standard","I17";
;
CDS_LIB"standard"
BODY_TYPE"PLUMBING"
HDL_TAP"TRUE";
"B \NAC \NWC"9;
"S \NAC"
BN"6"92;
%"TAP"
"1","(-175,375)","2","standard","I18";
;
CDS_LIB"standard"
BODY_TYPE"PLUMBING"
HDL_TAP"TRUE";
"B \NAC \NWC"9;
"S \NAC"
BN"7"91;
%"TAP"
"1","(-175,525)","2","standard","I19";
;
CDS_LIB"standard"
BODY_TYPE"PLUMBING"
HDL_TAP"TRUE";
"B \NAC \NWC"10;
"S \NAC"
BN"2"88;
%"TAP"
"1","(-175,-225)","2","standard","I2";
;
CDS_LIB"standard"
BODY_TYPE"PLUMBING"
HDL_TAP"TRUE";
"B \NAC \NWC"14;
"S \NAC"
BN"0"16;
%"TAP"
"1","(-175,575)","2","standard","I20";
;
CDS_LIB"standard"
BODY_TYPE"PLUMBING"
HDL_TAP"TRUE";
"B \NAC \NWC"10;
"S \NAC"
BN"3"87;
%"TAP"
"1","(-175,625)","2","standard","I21";
;
CDS_LIB"standard"
BODY_TYPE"PLUMBING"
HDL_TAP"TRUE";
"B \NAC \NWC"10;
"S \NAC"
BN"4"86;
%"TAP"
"1","(-175,725)","2","standard","I22";
;
CDS_LIB"standard"
BODY_TYPE"PLUMBING"
HDL_TAP"TRUE";
"B \NAC \NWC"10;
"S \NAC"
BN"6"84;
%"TAP"
"1","(-175,675)","2","standard","I23";
;
CDS_LIB"standard"
BODY_TYPE"PLUMBING"
HDL_TAP"TRUE";
"B \NAC \NWC"10;
"S \NAC"
BN"5"85;
%"TAP"
"1","(-175,775)","2","standard","I24";
;
CDS_LIB"standard"
BODY_TYPE"PLUMBING"
HDL_TAP"TRUE";
"B \NAC \NWC"10;
"S \NAC"
BN"7"83;
%"TAP"
"1","(-175,825)","2","standard","I25";
;
CDS_LIB"standard"
BODY_TYPE"PLUMBING"
HDL_TAP"TRUE";
"B \NAC \NWC"10;
"S \NAC"
BN"8"82;
%"TAP"
"1","(-175,875)","2","standard","I26";
;
CDS_LIB"standard"
BODY_TYPE"PLUMBING"
HDL_TAP"TRUE";
"B \NAC \NWC"10;
"S \NAC"
BN"9"81;
%"TAP"
"1","(-175,925)","2","standard","I27";
;
CDS_LIB"standard"
BODY_TYPE"PLUMBING"
HDL_TAP"TRUE";
"B \NAC \NWC"10;
"S \NAC"
BN"10"80;
%"TAP"
"1","(-175,1025)","2","standard","I28";
;
CDS_LIB"standard"
BODY_TYPE"PLUMBING"
HDL_TAP"TRUE";
"B \NAC \NWC"10;
"S \NAC"
BN"12"78;
%"TAP"
"1","(-175,975)","2","standard","I29";
;
CDS_LIB"standard"
BODY_TYPE"PLUMBING"
HDL_TAP"TRUE";
"B \NAC \NWC"10;
"S \NAC"
BN"11"79;
%"TAP"
"1","(-175,1075)","2","standard","I30";
;
CDS_LIB"standard"
BODY_TYPE"PLUMBING"
HDL_TAP"TRUE";
"B \NAC \NWC"10;
"S \NAC"
BN"13"77;
%"TAP"
"1","(-175,1125)","2","standard","I31";
;
CDS_LIB"standard"
BODY_TYPE"PLUMBING"
HDL_TAP"TRUE";
"B \NAC \NWC"10;
"S \NAC"
BN"14"76;
%"TAP"
"1","(-175,1175)","2","standard","I32";
;
CDS_LIB"standard"
BODY_TYPE"PLUMBING"
HDL_TAP"TRUE";
"B \NAC \NWC"10;
"S \NAC"
BN"15"75;
%"TAP"
"1","(-175,1225)","2","standard","I33";
;
CDS_LIB"standard"
BODY_TYPE"PLUMBING"
HDL_TAP"TRUE";
"B \NAC \NWC"10;
"S \NAC"
BN"16"74;
%"TAP"
"1","(-175,1275)","2","standard","I34";
;
CDS_LIB"standard"
BODY_TYPE"PLUMBING"
HDL_TAP"TRUE";
"B \NAC \NWC"10;
"S \NAC"
BN"17"73;
%"TAP"
"1","(-175,1325)","2","standard","I35";
;
CDS_LIB"standard"
BODY_TYPE"PLUMBING"
HDL_TAP"TRUE";
"B \NAC \NWC"10;
"S \NAC"
BN"18"72;
%"TAP"
"1","(-175,1375)","2","standard","I36";
;
CDS_LIB"standard"
BODY_TYPE"PLUMBING"
HDL_TAP"TRUE";
"B \NAC \NWC"10;
"S \NAC"
BN"19"71;
%"TAP"
"1","(-175,1425)","2","standard","I37";
;
CDS_LIB"standard"
BODY_TYPE"PLUMBING"
HDL_TAP"TRUE";
"B \NAC \NWC"10;
"S \NAC"
BN"20"70;
%"TAP"
"1","(-175,1475)","2","standard","I38";
;
CDS_LIB"standard"
BODY_TYPE"PLUMBING"
HDL_TAP"TRUE";
"B \NAC \NWC"10;
"S \NAC"
BN"21"69;
%"TAP"
"1","(-175,1525)","2","standard","I39";
;
CDS_LIB"standard"
BODY_TYPE"PLUMBING"
HDL_TAP"TRUE";
"B \NAC \NWC"10;
"S \NAC"
BN"22"68;
%"TAP"
"1","(-175,1575)","2","standard","I40";
;
CDS_LIB"standard"
BODY_TYPE"PLUMBING"
HDL_TAP"TRUE";
"B \NAC \NWC"10;
"S \NAC"
BN"23"67;
%"TAP"
"1","(-175,1625)","2","standard","I41";
;
CDS_LIB"standard"
BODY_TYPE"PLUMBING"
HDL_TAP"TRUE";
"B \NAC \NWC"10;
"S \NAC"
BN"24"66;
%"TAP"
"1","(-175,1675)","2","standard","I42";
;
CDS_LIB"standard"
BODY_TYPE"PLUMBING"
HDL_TAP"TRUE";
"B \NAC \NWC"10;
"S \NAC"
BN"25"65;
%"TAP"
"1","(-175,1725)","2","standard","I43";
;
CDS_LIB"standard"
BODY_TYPE"PLUMBING"
HDL_TAP"TRUE";
"B \NAC \NWC"10;
"S \NAC"
BN"26"64;
%"TAP"
"1","(-175,1775)","2","standard","I44";
;
CDS_LIB"standard"
BODY_TYPE"PLUMBING"
HDL_TAP"TRUE";
"B \NAC \NWC"10;
"S \NAC"
BN"27"63;
%"TAP"
"1","(-175,1875)","2","standard","I47";
;
CDS_LIB"standard"
BODY_TYPE"PLUMBING"
HDL_TAP"TRUE";
"B \NAC \NWC"10;
"S \NAC"
BN"29"61;
%"TAP"
"1","(-175,1925)","2","standard","I48";
;
CDS_LIB"standard"
BODY_TYPE"PLUMBING"
HDL_TAP"TRUE";
"B \NAC \NWC"10;
"S \NAC"
BN"30"60;
%"TAP"
"1","(-175,1825)","2","standard","I49";
;
CDS_LIB"standard"
BODY_TYPE"PLUMBING"
HDL_TAP"TRUE";
"B \NAC \NWC"10;
"S \NAC"
BN"28"62;
%"TAP"
"1","(-175,2025)","2","standard","I50";
;
CDS_LIB"standard"
BODY_TYPE"PLUMBING"
HDL_TAP"TRUE";
"B \NAC \NWC"11;
"S \NAC"
BN"0"58;
%"TAP"
"1","(-175,1975)","2","standard","I51";
;
CDS_LIB"standard"
BODY_TYPE"PLUMBING"
HDL_TAP"TRUE";
"B \NAC \NWC"10;
"S \NAC"
BN"31"59;
%"TAP"
"1","(-175,2075)","2","standard","I52";
;
CDS_LIB"standard"
BODY_TYPE"PLUMBING"
HDL_TAP"TRUE";
"B \NAC \NWC"11;
"S \NAC"
BN"1"57;
%"TAP"
"1","(-175,2125)","2","standard","I53";
;
CDS_LIB"standard"
BODY_TYPE"PLUMBING"
HDL_TAP"TRUE";
"B \NAC \NWC"11;
"S \NAC"
BN"2"56;
%"TAP"
"1","(-175,2175)","2","standard","I54";
;
CDS_LIB"standard"
BODY_TYPE"PLUMBING"
HDL_TAP"TRUE";
"B \NAC \NWC"11;
"S \NAC"
BN"3"55;
%"TAP"
"1","(-175,2275)","2","standard","I55";
;
CDS_LIB"standard"
BODY_TYPE"PLUMBING"
HDL_TAP"TRUE";
"B \NAC \NWC"11;
"S \NAC"
BN"5"53;
%"TAP"
"1","(-175,2225)","2","standard","I56";
;
CDS_LIB"standard"
BODY_TYPE"PLUMBING"
HDL_TAP"TRUE";
"B \NAC \NWC"11;
"S \NAC"
BN"4"54;
%"TAP"
"1","(-175,2325)","2","standard","I57";
;
CDS_LIB"standard"
BODY_TYPE"PLUMBING"
HDL_TAP"TRUE";
"B \NAC \NWC"11;
"S \NAC"
BN"6"52;
%"TAP"
"1","(-175,2525)","2","standard","I58";
;
CDS_LIB"standard"
BODY_TYPE"PLUMBING"
HDL_TAP"TRUE";
"B \NAC \NWC"12;
"S \NAC"
BN"2"48;
%"TAP"
"1","(-175,2475)","2","standard","I59";
;
CDS_LIB"standard"
BODY_TYPE"PLUMBING"
HDL_TAP"TRUE";
"B \NAC \NWC"12;
"S \NAC"
BN"1"49;
%"TAP"
"1","(-175,-125)","2","standard","I6";
;
CDS_LIB"standard"
BODY_TYPE"PLUMBING"
HDL_TAP"TRUE";
"B \NAC \NWC"13;
"S \NAC"
BN"0"18;
%"TAP"
"1","(-175,2425)","2","standard","I60";
;
CDS_LIB"standard"
BODY_TYPE"PLUMBING"
HDL_TAP"TRUE";
"B \NAC \NWC"12;
"S \NAC"
BN"0"50;
%"TAP"
"1","(-175,2375)","2","standard","I61";
;
CDS_LIB"standard"
BODY_TYPE"PLUMBING"
HDL_TAP"TRUE";
"B \NAC \NWC"11;
"S \NAC"
BN"7"51;
%"TAP"
"1","(-175,2575)","2","standard","I62";
;
CDS_LIB"standard"
BODY_TYPE"PLUMBING"
HDL_TAP"TRUE";
"B \NAC \NWC"12;
"S \NAC"
BN"3"47;
%"TAP"
"1","(-175,2625)","2","standard","I63";
;
CDS_LIB"standard"
BODY_TYPE"PLUMBING"
HDL_TAP"TRUE";
"B \NAC \NWC"12;
"S \NAC"
BN"4"46;
%"TAP"
"1","(-175,2675)","2","standard","I64";
;
CDS_LIB"standard"
BODY_TYPE"PLUMBING"
HDL_TAP"TRUE";
"B \NAC \NWC"12;
"S \NAC"
BN"5"45;
%"TAP"
"1","(-175,2775)","2","standard","I65";
;
CDS_LIB"standard"
BODY_TYPE"PLUMBING"
HDL_TAP"TRUE";
"B \NAC \NWC"12;
"S \NAC"
BN"7"43;
%"TAP"
"1","(-175,2725)","2","standard","I66";
;
CDS_LIB"standard"
BODY_TYPE"PLUMBING"
HDL_TAP"TRUE";
"B \NAC \NWC"12;
"S \NAC"
BN"6"44;
%"TAP"
"1","(-175,2825)","2","standard","I67";
;
CDS_LIB"standard"
BODY_TYPE"PLUMBING"
HDL_TAP"TRUE";
"B \NAC \NWC"12;
"S \NAC"
BN"8"42;
%"TAP"
"1","(-175,2925)","2","standard","I68";
;
CDS_LIB"standard"
BODY_TYPE"PLUMBING"
HDL_TAP"TRUE";
"B \NAC \NWC"12;
"S \NAC"
BN"10"40;
%"TAP"
"1","(-175,2875)","2","standard","I69";
;
CDS_LIB"standard"
BODY_TYPE"PLUMBING"
HDL_TAP"TRUE";
"B \NAC \NWC"12;
"S \NAC"
BN"9"41;
%"TAP"
"1","(-175,-75)","2","standard","I7";
;
CDS_LIB"standard"
BODY_TYPE"PLUMBING"
HDL_TAP"TRUE";
"B \NAC \NWC"13;
"S \NAC"
BN"1"17;
%"TAP"
"1","(-175,3075)","2","standard","I70";
;
CDS_LIB"standard"
BODY_TYPE"PLUMBING"
HDL_TAP"TRUE";
"B \NAC \NWC"12;
"S \NAC"
BN"13"37;
%"TAP"
"1","(-175,2975)","2","standard","I71";
;
CDS_LIB"standard"
BODY_TYPE"PLUMBING"
HDL_TAP"TRUE";
"B \NAC \NWC"12;
"S \NAC"
BN"11"39;
%"TAP"
"1","(-175,3025)","2","standard","I72";
;
CDS_LIB"standard"
BODY_TYPE"PLUMBING"
HDL_TAP"TRUE";
"B \NAC \NWC"12;
"S \NAC"
BN"12"38;
%"TAP"
"1","(-175,3125)","2","standard","I73";
;
CDS_LIB"standard"
BODY_TYPE"PLUMBING"
HDL_TAP"TRUE";
"B \NAC \NWC"12;
"S \NAC"
BN"14"36;
%"TAP"
"1","(-175,3175)","2","standard","I74";
;
CDS_LIB"standard"
BODY_TYPE"PLUMBING"
HDL_TAP"TRUE";
"B \NAC \NWC"12;
"S \NAC"
BN"15"35;
%"TAP"
"1","(-175,3325)","2","standard","I75";
;
CDS_LIB"standard"
BODY_TYPE"PLUMBING"
HDL_TAP"TRUE";
"B \NAC \NWC"12;
"S \NAC"
BN"18"32;
%"TAP"
"1","(-175,3275)","2","standard","I76";
;
CDS_LIB"standard"
BODY_TYPE"PLUMBING"
HDL_TAP"TRUE";
"B \NAC \NWC"12;
"S \NAC"
BN"17"33;
%"TAP"
"1","(-175,3225)","2","standard","I77";
;
CDS_LIB"standard"
BODY_TYPE"PLUMBING"
HDL_TAP"TRUE";
"B \NAC \NWC"12;
"S \NAC"
BN"16"34;
%"TAP"
"1","(-175,3375)","2","standard","I78";
;
CDS_LIB"standard"
BODY_TYPE"PLUMBING"
HDL_TAP"TRUE";
"B \NAC \NWC"12;
"S \NAC"
BN"19"31;
%"TAP"
"1","(-175,3425)","2","standard","I79";
;
CDS_LIB"standard"
BODY_TYPE"PLUMBING"
HDL_TAP"TRUE";
"B \NAC \NWC"12;
"S \NAC"
BN"20"30;
%"TAP"
"1","(-175,-175)","2","standard","I8";
;
CDS_LIB"standard"
BODY_TYPE"PLUMBING"
HDL_TAP"TRUE";
"B \NAC \NWC"14;
"S \NAC"
BN"1"15;
%"TAP"
"1","(-175,3575)","2","standard","I80";
;
CDS_LIB"standard"
BODY_TYPE"PLUMBING"
HDL_TAP"TRUE";
"B \NAC \NWC"12;
"S \NAC"
BN"23"27;
%"TAP"
"1","(-175,3525)","2","standard","I81";
;
CDS_LIB"standard"
BODY_TYPE"PLUMBING"
HDL_TAP"TRUE";
"B \NAC \NWC"12;
"S \NAC"
BN"22"28;
%"TAP"
"1","(-175,3475)","2","standard","I82";
;
CDS_LIB"standard"
BODY_TYPE"PLUMBING"
HDL_TAP"TRUE";
"B \NAC \NWC"12;
"S \NAC"
BN"21"29;
%"TAP"
"1","(-175,3625)","2","standard","I83";
;
CDS_LIB"standard"
BODY_TYPE"PLUMBING"
HDL_TAP"TRUE";
"B \NAC \NWC"12;
"S \NAC"
BN"24"26;
%"TAP"
"1","(-175,3675)","2","standard","I84";
;
CDS_LIB"standard"
BODY_TYPE"PLUMBING"
HDL_TAP"TRUE";
"B \NAC \NWC"12;
"S \NAC"
BN"25"25;
%"TAP"
"1","(-175,3775)","2","standard","I85";
;
CDS_LIB"standard"
BODY_TYPE"PLUMBING"
HDL_TAP"TRUE";
"B \NAC \NWC"12;
"S \NAC"
BN"27"23;
%"TAP"
"1","(-175,3825)","2","standard","I86";
;
CDS_LIB"standard"
BODY_TYPE"PLUMBING"
HDL_TAP"TRUE";
"B \NAC \NWC"12;
"S \NAC"
BN"28"22;
%"TAP"
"1","(-175,3725)","2","standard","I87";
;
CDS_LIB"standard"
BODY_TYPE"PLUMBING"
HDL_TAP"TRUE";
"B \NAC \NWC"12;
"S \NAC"
BN"26"24;
%"TAP"
"1","(-175,3875)","2","standard","I89";
;
CDS_LIB"standard"
BODY_TYPE"PLUMBING"
HDL_TAP"TRUE";
"B \NAC \NWC"12;
"S \NAC"
BN"29"21;
%"TAP"
"1","(-175,25)","2","standard","I9";
;
CDS_LIB"standard"
BODY_TYPE"PLUMBING"
HDL_TAP"TRUE";
"B \NAC \NWC"9;
"S \NAC"
BN"0"98;
%"TAP"
"1","(-175,3925)","2","standard","I90";
;
CDS_LIB"standard"
BODY_TYPE"PLUMBING"
HDL_TAP"TRUE";
"B \NAC \NWC"12;
"S \NAC"
BN"30"20;
%"TAP"
"1","(-175,3975)","2","standard","I91";
;
CDS_LIB"standard"
BODY_TYPE"PLUMBING"
HDL_TAP"TRUE";
"B \NAC \NWC"12;
"S \NAC"
BN"31"19;
%"TAP"
"1","(3250,275)","0","standard","I93";
;
CDS_LIB"standard"
BODY_TYPE"PLUMBING"
HDL_TAP"TRUE";
"B \NAC \NWC"6;
"S \NAC"
BN"1"121;
%"TAP"
"1","(3250,225)","0","standard","I94";
;
CDS_LIB"standard"
BODY_TYPE"PLUMBING"
HDL_TAP"TRUE";
"B \NAC \NWC"6;
"S \NAC"
BN"0"120;
%"TAP"
"1","(3250,375)","0","standard","I95";
;
CDS_LIB"standard"
BODY_TYPE"PLUMBING"
HDL_TAP"TRUE";
"B \NAC \NWC"6;
"S \NAC"
BN"3"123;
%"TAP"
"1","(3250,325)","0","standard","I96";
;
CDS_LIB"standard"
BODY_TYPE"PLUMBING"
HDL_TAP"TRUE";
"B \NAC \NWC"6;
"S \NAC"
BN"2"122;
%"TAP"
"1","(3250,525)","0","standard","I97";
;
CDS_LIB"standard"
BODY_TYPE"PLUMBING"
HDL_TAP"TRUE";
"B \NAC \NWC"2;
"S \NAC"
BN"0"152;
%"TAP"
"1","(3250,625)","0","standard","I98";
;
CDS_LIB"standard"
BODY_TYPE"PLUMBING"
HDL_TAP"TRUE";
"B \NAC \NWC"2;
"S \NAC"
BN"2"154;
%"TAP"
"1","(3250,575)","0","standard","I99";
;
CDS_LIB"standard"
BODY_TYPE"PLUMBING"
HDL_TAP"TRUE";
"B \NAC \NWC"2;
"S \NAC"
BN"1"153;
END.
